(kicad_pcb
	(version 20260206)
	(generator "pcbnew")
	(generator_version "10.0")
	(general
		(thickness 1.6)
		(legacy_teardrops no)
	)
	(paper "A4")
	(title_block
		(title "Bryce Canyon_F.DPB_16315-1-OCP.brd")
		(comment 1 "Bryce Canyon / footprints 1295-1301 of 2223")
	)
	(layers
		(0 "F.Cu" signal "TOP")
		(4 "In1.Cu" signal "L2GND")
		(6 "In2.Cu" signal "L3")
		(8 "In3.Cu" signal "L4GND")
		(10 "In4.Cu" signal "L5")
		(12 "In5.Cu" signal "L6VCC")
		(14 "In6.Cu" signal "L7VCC")
		(16 "In7.Cu" signal "L8")
		(18 "In8.Cu" signal "L9GND")
		(20 "In9.Cu" signal "L10")
		(22 "In10.Cu" signal "L11GND")
		(2 "B.Cu" signal "BOTTOM")
		(9 "F.Adhes" user "F.Adhesive")
		(11 "B.Adhes" user "B.Adhesive")
		(13 "F.Paste" user "Package Geometry/Pastemask Top")
		(15 "B.Paste" user "Package Geometry/Pastemask Bottom")
		(5 "F.SilkS" user "Ref Des/Silkscreen Top")
		(7 "B.SilkS" user "Ref Des/Silkscreen Bottom")
		(1 "F.Mask" user "Board Geometry/Soldermask Top")
		(3 "B.Mask" user "Board Geometry/Soldermask Bottom")
		(17 "Dwgs.User" user "User.Drawings")
		(19 "Cmts.User" user "User.Comments")
		(21 "Eco1.User" user "User.Eco1")
		(23 "Eco2.User" user "User.Eco2")
		(25 "Edge.Cuts" user "Board Geometry/Outline")
		(27 "Margin" user)
		(31 "F.CrtYd" user "Package Geometry/Place Bound Top")
		(29 "B.CrtYd" user "Package Geometry/Place Bound Bottom")
		(35 "F.Fab" user "Ref Des/Assembly Top")
		(33 "B.Fab" user "Ref Des/Assembly Bottom")
	)
	(footprint ""
		(layer "F.Cu")
		(at 129.697734 -127.798068 180)
		(property "Reference" "Q279"
			(at 0 0 180)
			(layer "F.SilkS")
			(hide yes)
			(effects
				(font
					(size 1.27 1.27)
				)
			)
		)
		(property "Value" "SSM3K324R-GP"
			(at 0.127 -8.9662 180)
			(unlocked yes)
			(layer "F.Fab")
			(hide yes)
			(effects
				(font
					(size 1.016 1.016)
					(thickness 0.1524)
				)
			)
		)
		(property "Device Type" "SOT23DGS2D4H35"
			(at 0.127 -10.4902 180)
			(unlocked yes)
			(layer "F.Fab")
			(hide yes)
			(effects
				(font
					(size 1.016 1.016)
					(thickness 0.1524)
				)
			)
		)
		(duplicate_pad_numbers_are_jumpers no)
		(fp_line
			(start 1.651 1.778)
			(end 1.651 -1.778)
			(stroke
				(width 0.1524)
				(type default)
			)
			(layer "F.SilkS")
		)
		(fp_line
			(start 1.651 -1.778)
			(end -1.651 -1.778)
			(stroke
				(width 0.1524)
				(type default)
			)
			(layer "F.SilkS")
		)
		(fp_line
			(start -1.651 1.778)
			(end 1.651 1.778)
			(stroke
				(width 0.1524)
				(type default)
			)
			(layer "F.SilkS")
		)
		(fp_line
			(start -1.651 -1.778)
			(end -1.651 1.778)
			(stroke
				(width 0.1524)
				(type default)
			)
			(layer "F.SilkS")
		)
		(fp_poly
			(pts
				(xy -1.778 1.8796) (xy -1.778 -1.8796) (xy 1.778 -1.8796) (xy 1.778 1.8796)
			)
			(stroke
				(width 0)
				(type default)
			)
			(fill no)
			(layer "F.CrtYd")
		)
		(fp_poly
			(pts
				(xy -1.778 1.8796) (xy -1.778 -1.8796) (xy 1.778 -1.8796) (xy 1.778 1.8796)
			)
			(stroke
				(width 0)
				(type default)
			)
			(fill no)
			(layer "F.Fab")
		)
		(pad "D" smd custom
			(at 0 -0.9525 180)
			(size 0.1905 0.1905)
			(layers "F.Cu" "F.Mask" "F.Paste")
			(net "DRV_ACT_16_N")
			(options
				(clearance outline)
				(anchor circle)
			)
			(primitives
				(gr_poly
					(pts
						(arc
							(start -0.1778 0.5715)
							(mid -0.321484 0.511984)
							(end -0.381 0.3683)
						)
						(arc
							(start -0.381 -0.3683)
							(mid -0.321484 -0.511984)
							(end -0.1778 -0.5715)
						)
						(arc
							(start 0.1778 -0.5715)
							(mid 0.321484 -0.511984)
							(end 0.381 -0.3683)
						)
						(arc
							(start 0.381 0.3683)
							(mid 0.321484 0.511984)
							(end 0.1778 0.5715)
						)
					)
					(width 0)
					(fill yes)
				)
			)
		)
		(pad "G" smd custom
			(at -0.98425 0.9525 180)
			(size 0.1905 0.1905)
			(layers "F.Cu" "F.Mask" "F.Paste")
			(net "DRIVE_A_16_ACT")
			(options
				(clearance outline)
				(anchor circle)
			)
			(primitives
				(gr_poly
					(pts
						(arc
							(start -0.1778 0.5715)
							(mid -0.321484 0.511984)
							(end -0.381 0.3683)
						)
						(arc
							(start -0.381 -0.3683)
							(mid -0.321484 -0.511984)
							(end -0.1778 -0.5715)
						)
						(arc
							(start 0.1778 -0.5715)
							(mid 0.321484 -0.511984)
							(end 0.381 -0.3683)
						)
						(arc
							(start 0.381 0.3683)
							(mid 0.321484 0.511984)
							(end 0.1778 0.5715)
						)
					)
					(width 0)
					(fill yes)
				)
			)
		)
		(pad "S" smd custom
			(at 0.98425 0.9525 180)
			(size 0.1905 0.1905)
			(layers "F.Cu" "F.Mask" "F.Paste")
			(net "GND")
			(options
				(clearance outline)
				(anchor circle)
			)
			(primitives
				(gr_poly
					(pts
						(arc
							(start -0.1778 0.5715)
							(mid -0.321484 0.511984)
							(end -0.381 0.3683)
						)
						(arc
							(start -0.381 -0.3683)
							(mid -0.321484 -0.511984)
							(end -0.1778 -0.5715)
						)
						(arc
							(start 0.1778 -0.5715)
							(mid 0.321484 -0.511984)
							(end 0.381 -0.3683)
						)
						(arc
							(start 0.381 0.3683)
							(mid 0.321484 0.511984)
							(end 0.1778 0.5715)
						)
					)
					(width 0)
					(fill yes)
				)
			)
		)
	)
	(footprint ""
		(layer "F.Cu")
		(at 337.312 -47.792894 90)
		(property "Reference" "D30"
			(at 0 0 90)
			(layer "F.SilkS")
			(hide yes)
			(effects
				(font
					(size 1.27 1.27)
				)
			)
		)
		(property "Value" "RB551V30-GP"
			(at 0 -6.7818 90)
			(unlocked yes)
			(layer "F.Fab")
			(hide yes)
			(effects
				(font
					(size 1.016 1.016)
					(thickness 0.1524)
				)
			)
		)
		(property "Device Type" "SOD323AKH38"
			(at 0 -8.6868 90)
			(unlocked yes)
			(layer "F.Fab")
			(hide yes)
			(effects
				(font
					(size 1.016 1.016)
					(thickness 0.1524)
				)
			)
		)
		(duplicate_pad_numbers_are_jumpers no)
		(fp_line
			(start 0.889 -1.9304)
			(end 0.889 2.159)
			(stroke
				(width 0.1524)
				(type default)
			)
			(layer "F.SilkS")
		)
		(fp_line
			(start -0.889 -1.9304)
			(end 0.889 -1.9304)
			(stroke
				(width 0.1524)
				(type default)
			)
			(layer "F.SilkS")
		)
		(fp_line
			(start 0.762 2.0574)
			(end -0.762 2.0574)
			(stroke
				(width 0.508)
				(type default)
			)
			(layer "F.SilkS")
		)
		(fp_line
			(start 0.889 2.159)
			(end -0.889 2.159)
			(stroke
				(width 0.1524)
				(type default)
			)
			(layer "F.SilkS")
		)
		(fp_line
			(start -0.889 2.159)
			(end -0.889 -1.9304)
			(stroke
				(width 0.1524)
				(type default)
			)
			(layer "F.SilkS")
		)
		(fp_rect
			(start -1.016 2.3114)
			(end 1.016 -2.0066)
			(stroke
				(width 0)
				(type default)
			)
			(fill no)
			(layer "F.CrtYd")
		)
		(fp_poly
			(pts
				(xy -1.016 -2.0066) (xy 1.016 -2.0066) (xy 1.016 2.3114) (xy -1.016 2.3114)
			)
			(stroke
				(width 0)
				(type default)
			)
			(fill no)
			(layer "F.Fab")
		)
		(pad "A" smd rect
			(at 0 -1.143 90)
			(size 0.5588 1.016)
			(layers "F.Cu" "F.Mask" "F.Paste")
			(net "SW_HDD_R30")
		)
		(pad "K" smd rect
			(at 0 1.143 90)
			(size 0.5588 1.016)
			(layers "F.Cu" "F.Mask" "F.Paste")
			(net "SW_HDD_N30")
		)
	)
	(footprint ""
		(layer "F.Cu")
		(at 368.354102 -177.016918)
		(property "Reference" "Q116"
			(at 0 0 0)
			(layer "F.SilkS")
			(hide yes)
			(effects
				(font
					(size 1.27 1.27)
				)
			)
		)
		(property "Value" "AO4407AL-GP"
			(at -3.707384 -1.5367 0)
			(unlocked yes)
			(layer "F.Fab")
			(hide yes)
			(effects
				(font
					(size 1.016 1.016)
					(thickness 0.1524)
				)
			)
		)
		(property "Device Type" "SOIC8H69"
			(at -3.707384 -3.0607 0)
			(unlocked yes)
			(layer "F.Fab")
			(hide yes)
			(effects
				(font
					(size 1.016 1.016)
					(thickness 0.1524)
				)
			)
		)
		(duplicate_pad_numbers_are_jumpers no)
		(fp_line
			(start -2.7432 -1.4224)
			(end -2.7432 1.4224)
			(stroke
				(width 0.1524)
				(type default)
			)
			(layer "F.SilkS")
		)
		(fp_line
			(start -2.7432 1.4224)
			(end -2.6416 1.4224)
			(stroke
				(width 0.1524)
				(type default)
			)
			(layer "F.SilkS")
		)
		(fp_line
			(start -2.7432 1.4224)
			(end 2.1336 1.4224)
			(stroke
				(width 0.1524)
				(type default)
			)
			(layer "F.SilkS")
		)
		(fp_line
			(start -2.7178 -0.508)
			(end -2.1844 -0.0508)
			(stroke
				(width 0.1524)
				(type default)
			)
			(layer "F.SilkS")
		)
		(fp_line
			(start -2.6289 3.4417)
			(end -2.6289 1.4732)
			(stroke
				(width 0.381)
				(type default)
			)
			(layer "F.SilkS")
		)
		(fp_line
			(start -2.1844 -0.0508)
			(end -2.7178 0.508)
			(stroke
				(width 0.1524)
				(type default)
			)
			(layer "F.SilkS")
		)
		(fp_line
			(start 2.1336 -1.4224)
			(end -2.7432 -1.4224)
			(stroke
				(width 0.1524)
				(type default)
			)
			(layer "F.SilkS")
		)
		(fp_line
			(start 2.1336 1.4224)
			(end 2.1336 -1.4224)
			(stroke
				(width 0.1524)
				(type default)
			)
			(layer "F.SilkS")
		)
		(fp_poly
			(pts
				(xy -2.2098 -1.4224) (xy -2.2098 1.4224) (xy 2.2098 1.4224) (xy 2.2098 -1.4224)
			)
			(stroke
				(width 0)
				(type default)
			)
			(fill yes)
			(layer "F.SilkS")
		)
		(fp_rect
			(start -2.450084 2.999994)
			(end 2.450084 -2.999994)
			(stroke
				(width 0)
				(type default)
			)
			(fill no)
			(layer "F.CrtYd")
		)
		(fp_poly
			(pts
				(xy -2.8194 3.6322) (xy -2.8194 -3.6322) (xy 2.8194 -3.6322) (xy 2.8194 1.18364) (xy 2.450084 1.18364)
				(xy 2.450084 -2.999994) (xy -2.450084 -2.999994) (xy -2.450084 2.999994) (xy 2.450084 2.999994)
				(xy 2.450084 1.18618) (xy 2.8194 1.18618) (xy 2.8194 3.6322)
			)
			(stroke
				(width 0)
				(type default)
			)
			(fill no)
			(layer "F.CrtYd")
		)
		(fp_rect
			(start -2.8194 3.6322)
			(end 2.8194 -3.6322)
			(stroke
				(width 0)
				(type default)
			)
			(fill no)
			(layer "F.Fab")
		)
		(pad "1" smd rect
			(at -1.905 2.54)
			(size 0.635 1.651)
			(layers "F.Cu" "F.Mask" "F.Paste")
			(net "P12V_A")
		)
		(pad "2" smd rect
			(at -0.635 2.54)
			(size 0.635 1.651)
			(layers "F.Cu" "F.Mask" "F.Paste")
			(net "P12V_A")
		)
		(pad "3" smd rect
			(at 0.635 2.54)
			(size 0.635 1.651)
			(layers "F.Cu" "F.Mask" "F.Paste")
			(net "P12V_A")
		)
		(pad "4" smd rect
			(at 1.905 2.54)
			(size 0.635 1.651)
			(layers "F.Cu" "F.Mask" "F.Paste")
			(net "SW_HDD_N19")
		)
		(pad "5" smd rect
			(at 1.905 -2.54)
			(size 0.635 1.651)
			(layers "F.Cu" "F.Mask" "F.Paste")
			(net "P12V_HDD19")
		)
		(pad "6" smd rect
			(at 0.635 -2.54)
			(size 0.635 1.651)
			(layers "F.Cu" "F.Mask" "F.Paste")
			(net "P12V_HDD19")
		)
		(pad "7" smd rect
			(at -0.635 -2.54)
			(size 0.635 1.651)
			(layers "F.Cu" "F.Mask" "F.Paste")
			(net "P12V_HDD19")
		)
		(pad "8" smd rect
			(at -1.905 -2.54)
			(size 0.635 1.651)
			(layers "F.Cu" "F.Mask" "F.Paste")
			(net "P12V_HDD19")
		)
	)
	(footprint ""
		(layer "F.Cu")
		(at 263.832848 10.225532 180)
		(property "Reference" "R135"
			(at 0 0 180)
			(layer "F.SilkS")
			(hide yes)
			(effects
				(font
					(size 1.27 1.27)
				)
			)
		)
		(property "Value" "4K7R2F-GP"
			(at 0.064008 -3.993896 180)
			(unlocked yes)
			(layer "F.Fab")
			(hide yes)
			(effects
				(font
					(size 1.016 1.016)
					(thickness 0.1524)
				)
			)
		)
		(property "Device Type" "R402H16"
			(at 0.064008 -5.517896 180)
			(unlocked yes)
			(layer "F.Fab")
			(hide yes)
			(effects
				(font
					(size 1.016 1.016)
					(thickness 0.1524)
				)
			)
		)
		(duplicate_pad_numbers_are_jumpers no)
		(fp_line
			(start 0.508 -0.9398)
			(end -0.508 -0.9398)
			(stroke
				(width 0.1524)
				(type default)
			)
			(layer "F.SilkS")
		)
		(fp_line
			(start -0.508 -0.9398)
			(end -0.508 0.9398)
			(stroke
				(width 0.1524)
				(type default)
			)
			(layer "F.SilkS")
		)
		(fp_rect
			(start -0.508 0.9398)
			(end 0.508 -0.9398)
			(stroke
				(width 0)
				(type default)
			)
			(fill no)
			(layer "F.CrtYd")
		)
		(fp_rect
			(start -0.508 0.9398)
			(end 0.508 -0.9398)
			(stroke
				(width 0)
				(type default)
			)
			(fill no)
			(layer "F.Fab")
		)
		(pad "1" smd custom
			(at 0 -0.4445 180)
			(size 0.1397 0.1397)
			(layers "F.Cu" "F.Mask" "F.Paste")
			(net "USB_EN_1")
			(options
				(clearance outline)
				(anchor circle)
			)
			(primitives
				(gr_poly
					(pts
						(arc
							(start -0.1778 -0.2794)
							(mid -0.249642 -0.249642)
							(end -0.2794 -0.1778)
						)
						(arc
							(start -0.2794 0.1778)
							(mid -0.249642 0.249642)
							(end -0.1778 0.2794)
						)
						(arc
							(start 0.1778 0.2794)
							(mid 0.249642 0.249642)
							(end 0.2794 0.1778)
						)
						(arc
							(start 0.2794 -0.1778)
							(mid 0.249642 -0.249642)
							(end 0.1778 -0.2794)
						)
					)
					(width 0)
					(fill yes)
				)
			)
		)
		(pad "2" smd custom
			(at 0 0.4445 180)
			(size 0.1397 0.1397)
			(layers "F.Cu" "F.Mask" "F.Paste")
			(net "GND")
			(options
				(clearance outline)
				(anchor circle)
			)
			(primitives
				(gr_poly
					(pts
						(arc
							(start -0.1778 -0.2794)
							(mid -0.249642 -0.249642)
							(end -0.2794 -0.1778)
						)
						(arc
							(start -0.2794 0.1778)
							(mid -0.249642 0.249642)
							(end -0.1778 0.2794)
						)
						(arc
							(start 0.1778 0.2794)
							(mid 0.249642 0.249642)
							(end 0.2794 0.1778)
						)
						(arc
							(start 0.2794 -0.1778)
							(mid 0.249642 -0.249642)
							(end 0.1778 -0.2794)
						)
					)
					(width 0)
					(fill yes)
				)
			)
		)
	)
	(footprint ""
		(layer "F.Cu")
		(at 247.849644 -143.49984)
		(property "Reference" ""
			(at 0 0 0)
			(layer "F.SilkS")
			(hide yes)
			(effects
				(font
					(size 1.27 1.27)
				)
			)
		)
		(property "Value" "*"
			(at 5.4229 -0.7239 0)
			(unlocked yes)
			(layer "F.Fab")
			(hide yes)
			(effects
				(font
					(size 1.016 1.016)
					(thickness 0.1524)
				)
			)
		)
		(duplicate_pad_numbers_are_jumpers no)
		(fp_poly
			(pts
				(arc
					(start 4.064 0)
					(mid -4.064 0)
					(end 4.064 0)
				)
			)
			(stroke
				(width 0)
				(type default)
			)
			(fill no)
			(layer "B.CrtYd")
		)
		(fp_poly
			(pts
				(arc
					(start 4.064 0)
					(mid -4.064 0)
					(end 4.064 0)
				)
			)
			(stroke
				(width 0)
				(type default)
			)
			(fill no)
			(layer "F.CrtYd")
		)
		(fp_poly
			(pts
				(arc
					(start 4.064 0)
					(mid -4.064 0)
					(end 4.064 0)
				)
			)
			(stroke
				(width 0)
				(type default)
			)
			(fill no)
			(layer "B.Fab")
		)
		(fp_poly
			(pts
				(arc
					(start 4.064 0)
					(mid -4.064 0)
					(end 4.064 0)
				)
			)
			(stroke
				(width 0)
				(type default)
			)
			(fill no)
			(layer "F.Fab")
		)
		(pad "1" thru_hole circle
			(at 0 0)
			(size 7.5184 7.5184)
			(drill 3.0226)
			(layers "*.Cu" "*.Mask")
			(remove_unused_layers no)
			(net "Net_63")
			(clearance -1.7399)
			(thermal_gap 0.3048)
			(padstack
				(mode front_inner_back)
				(layer "Inner"
					(shape circle)
					(size 3.429 3.429)
					(clearance 0.3048)
				)
				(layer "B.Cu"
					(shape circle)
					(size 7.5184 7.5184)
					(clearance -1.7399)
				)
			)
		)
	)
	(footprint ""
		(layer "F.Cu")
		(at 364.798102 -272.585942 180)
		(property "Reference" "R299"
			(at 0 0 180)
			(layer "F.SilkS")
			(hide yes)
			(effects
				(font
					(size 1.27 1.27)
				)
			)
		)
		(property "Value" "1KR2F-3-GP"
			(at 0.064008 -3.993896 180)
			(unlocked yes)
			(layer "F.Fab")
			(hide yes)
			(effects
				(font
					(size 1.016 1.016)
					(thickness 0.1524)
				)
			)
		)
		(property "Device Type" "R402H16"
			(at 0.064008 -5.517896 180)
			(unlocked yes)
			(layer "F.Fab")
			(hide yes)
			(effects
				(font
					(size 1.016 1.016)
					(thickness 0.1524)
				)
			)
		)
		(duplicate_pad_numbers_are_jumpers no)
		(fp_line
			(start 0.508 -0.9398)
			(end -0.508 -0.9398)
			(stroke
				(width 0.1524)
				(type default)
			)
			(layer "F.SilkS")
		)
		(fp_line
			(start -0.508 -0.9398)
			(end -0.508 0.9398)
			(stroke
				(width 0.1524)
				(type default)
			)
			(layer "F.SilkS")
		)
		(fp_rect
			(start -0.508 0.9398)
			(end 0.508 -0.9398)
			(stroke
				(width 0)
				(type default)
			)
			(fill no)
			(layer "F.CrtYd")
		)
		(fp_rect
			(start -0.508 0.9398)
			(end 0.508 -0.9398)
			(stroke
				(width 0)
				(type default)
			)
			(fill no)
			(layer "F.Fab")
		)
		(pad "1" smd custom
			(at 0 -0.4445 180)
			(size 0.1397 0.1397)
			(layers "F.Cu" "F.Mask" "F.Paste")
			(net "P3V3_STBY_A")
			(options
				(clearance outline)
				(anchor circle)
			)
			(primitives
				(gr_poly
					(pts
						(arc
							(start -0.1778 -0.2794)
							(mid -0.249642 -0.249642)
							(end -0.2794 -0.1778)
						)
						(arc
							(start -0.2794 0.1778)
							(mid -0.249642 0.249642)
							(end -0.1778 0.2794)
						)
						(arc
							(start 0.1778 0.2794)
							(mid 0.249642 0.249642)
							(end 0.2794 0.1778)
						)
						(arc
							(start 0.2794 -0.1778)
							(mid 0.249642 -0.249642)
							(end 0.1778 -0.2794)
						)
					)
					(width 0)
					(fill yes)
				)
			)
		)
		(pad "2" smd custom
			(at 0 0.4445 180)
			(size 0.1397 0.1397)
			(layers "F.Cu" "F.Mask" "F.Paste")
			(net "SW_PWR_R_HDD7")
			(options
				(clearance outline)
				(anchor circle)
			)
			(primitives
				(gr_poly
					(pts
						(arc
							(start -0.1778 -0.2794)
							(mid -0.249642 -0.249642)
							(end -0.2794 -0.1778)
						)
						(arc
							(start -0.2794 0.1778)
							(mid -0.249642 0.249642)
							(end -0.1778 0.2794)
						)
						(arc
							(start 0.1778 0.2794)
							(mid 0.249642 0.249642)
							(end 0.2794 0.1778)
						)
						(arc
							(start 0.2794 -0.1778)
							(mid 0.249642 -0.249642)
							(end 0.1778 -0.2794)
						)
					)
					(width 0)
					(fill yes)
				)
			)
		)
	)
	(footprint ""
		(layer "F.Cu")
		(at 384.734562 -274.219416 -90)
		(property "Reference" "C142"
			(at 0 0 270)
			(layer "F.SilkS")
			(hide yes)
			(effects
				(font
					(size 1.27 1.27)
				)
			)
		)
		(property "Value" "SCD01U16V1KX-GP"
			(at -2.8321 -1.7399 270)
			(unlocked yes)
			(layer "F.Fab")
			(hide yes)
			(effects
				(font
					(size 1.016 1.016)
					(thickness 0.1524)
				)
			)
		)
		(property "Device Type" "C0201H13"
			(at -2.8321 -3.2639 270)
			(unlocked yes)
			(layer "F.Fab")
			(hide yes)
			(effects
				(font
					(size 1.016 1.016)
					(thickness 0.1524)
				)
			)
		)
		(duplicate_pad_numbers_are_jumpers no)
		(fp_rect
			(start -0.2794 0.6477)
			(end 0.2794 -0.6477)
			(stroke
				(width 0)
				(type default)
			)
			(fill no)
			(layer "F.CrtYd")
		)
		(fp_rect
			(start -0.2794 0.6477)
			(end 0.2794 -0.6477)
			(stroke
				(width 0)
				(type default)
			)
			(fill no)
			(layer "F.Fab")
		)
		(pad "1" smd custom
			(at 0 -0.2794 270)
			(size 0.0762 0.0762)
			(layers "F.Cu" "F.Mask" "F.Paste")
			(net "SAS_HDD_RX_N8")
			(options
				(clearance outline)
				(anchor circle)
			)
			(primitives
				(gr_poly
					(pts
						(arc
							(start 0.1524 -0.127)
							(mid 0.137521 -0.162921)
							(end 0.1016 -0.1778)
						)
						(arc
							(start -0.1016 -0.1778)
							(mid -0.137521 -0.162921)
							(end -0.1524 -0.127)
						)
						(arc
							(start -0.1524 0.127)
							(mid -0.137521 0.162921)
							(end -0.1016 0.1778)
						)
						(arc
							(start 0.1016 0.1778)
							(mid 0.137521 0.162921)
							(end 0.1524 0.127)
						)
					)
					(width 0)
					(fill yes)
				)
			)
		)
		(pad "2" smd custom
			(at 0 0.2794 270)
			(size 0.0762 0.0762)
			(layers "F.Cu" "F.Mask" "F.Paste")
			(net "PHY_SCC_A_TO_DRV_A_8_DN")
			(options
				(clearance outline)
				(anchor circle)
			)
			(primitives
				(gr_poly
					(pts
						(arc
							(start 0.1524 -0.127)
							(mid 0.137521 -0.162921)
							(end 0.1016 -0.1778)
						)
						(arc
							(start -0.1016 -0.1778)
							(mid -0.137521 -0.162921)
							(end -0.1524 -0.127)
						)
						(arc
							(start -0.1524 0.127)
							(mid -0.137521 0.162921)
							(end -0.1016 0.1778)
						)
						(arc
							(start 0.1016 0.1778)
							(mid 0.137521 0.162921)
							(end 0.1524 0.127)
						)
					)
					(width 0)
					(fill yes)
				)
			)
		)
	)
)
